# S9S_MB_2U (Grand Teton) — schematic netlist excerpt (pin names and nets, part order shuffled) for the footprints in the layout excerpt that follows; sources: Cadence DE-HDL packaged netlist, KiCad conversion of 03242023_DA0F0TMBIJ0_F0T_Motherboard_J_brd_V01_OCP.brd

U82  74LVC1G126SE7  74LVC1G126SE-7 IC  pkg SOT353_0-65_2X1-25  page 155
  OE  = PU_OCP_SFF_WAKE_OE
  A  = IRQ_LVC3_OCP_SFF_WAKE_N
  GND  = GND
  Y  = OCP_SFF_WAKE_BUFF_N
  VCC  = P3V3_AUX

C737  Q_CAP_DIFFBUS  DIFF BUS_0.22UF 6.3V 20% X6S  pkg C0201  page 176 : \1\ = P5E_CPU1_PE0_TX_C_DP<2> ; \2\ = P5E_CPU1_PE0_TX_DP<2>
R2398  Q_RES  1K 1% CHIP  pkg 0402LF  page 274 : A = P3V3_AUX ; B = IRQ_PVCCFA_CPU0_VRHOT_R_N

(kicad_pcb
	(version 20260206)
	(generator "pcbnew")
	(generator_version "10.0")
	(general
		(thickness 1.6)
		(legacy_teardrops no)
	)
	(paper "A4")
	(title_block
		(title "03242023_DA0F0TMBIJ0_F0T_Motherboard_J_brd_V01_OCP.brd")
		(comment 1 "Grand Teton / footprints 3675-3677 of 6105")
	)
	(layers
		(0 "F.Cu" signal "TOP")
		(4 "In1.Cu" signal "GND")
		(6 "In2.Cu" signal "IN1")
		(8 "In3.Cu" signal "GND1")
		(10 "In4.Cu" signal "IN2")
		(12 "In5.Cu" signal "GND2")
		(14 "In6.Cu" signal "IN3")
		(16 "In7.Cu" signal "GND3")
		(18 "In8.Cu" signal "VCC")
		(20 "In9.Cu" signal "VCC1")
		(22 "In10.Cu" signal "GND4")
		(24 "In11.Cu" signal "IN4")
		(26 "In12.Cu" signal "GND5")
		(28 "In13.Cu" signal "IN5")
		(30 "In14.Cu" signal "GND6")
		(32 "In15.Cu" signal "IN6")
		(34 "In16.Cu" signal "GND7")
		(2 "B.Cu" signal "BOTTOM")
		(9 "F.Adhes" user "F.Adhesive")
		(11 "B.Adhes" user "B.Adhesive")
		(13 "F.Paste" user "Package Geometry/Pastemask Top")
		(15 "B.Paste" user "Package Geometry/Pastemask Bottom")
		(5 "F.SilkS" user "Ref Des/Silkscreen Top")
		(7 "B.SilkS" user "Ref Des/Silkscreen Bottom")
		(1 "F.Mask" user "Board Geometry/Soldermask Top")
		(3 "B.Mask" user "Board Geometry/Soldermask Bottom")
		(17 "Dwgs.User" user "User.Drawings")
		(19 "Cmts.User" user "User.Comments")
		(21 "Eco1.User" user "User.Eco1")
		(23 "Eco2.User" user "User.Eco2")
		(25 "Edge.Cuts" user "Board Geometry/Outline")
		(27 "Margin" user)
		(31 "F.CrtYd" user "Package Geometry/Place Bound Top")
		(29 "B.CrtYd" user "Package Geometry/Place Bound Bottom")
		(35 "F.Fab" user "Ref Des/Assembly Top")
		(33 "B.Fab" user "Ref Des/Assembly Bottom")
	)
	(footprint ""
		(layer "F.Cu")
		(at 88.690958 -402.371052 -90)
		(property "Reference" "C737"
			(at 0 0 270)
			(layer "F.SilkS")
			(hide yes)
			(effects
				(font
					(size 1.27 1.27)
				)
			)
		)
		(property "Value" ""
			(at 0 0 270)
			(layer "F.Fab")
			(effects
				(font
					(size 1.27 1.27)
				)
			)
		)
		(duplicate_pad_numbers_are_jumpers no)
		(fp_line
			(start -0.299974 0.150114)
			(end -0.299974 -0.150114)
			(stroke
				(width 0.1)
				(type default)
			)
			(layer "F.Fab")
		)
		(fp_line
			(start 0.299974 0.150114)
			(end -0.299974 0.150114)
			(stroke
				(width 0.1)
				(type default)
			)
			(layer "F.Fab")
		)
		(fp_line
			(start -0.299974 -0.150114)
			(end 0.299974 -0.150114)
			(stroke
				(width 0.1)
				(type default)
			)
			(layer "F.Fab")
		)
		(fp_line
			(start 0.299974 -0.150114)
			(end 0.299974 0.150114)
			(stroke
				(width 0.1)
				(type default)
			)
			(layer "F.Fab")
		)
		(pad "1" smd rect
			(at -0.2667 0 270)
			(size 0.3048 0.381)
			(layers "F.Cu" "F.Mask" "F.Paste")
			(net "P5E_CPU1_PE0_TX_C_DP<2>")
		)
		(pad "2" smd rect
			(at 0.2667 0 270)
			(size 0.3048 0.381)
			(layers "F.Cu" "F.Mask" "F.Paste")
			(net "P5E_CPU1_PE0_TX_DP<2>")
		)
	)
	(footprint ""
		(layer "F.Cu")
		(at 433.33289 -135.029702 180)
		(property "Reference" "R2398"
			(at 0 0 180)
			(layer "F.SilkS")
			(hide yes)
			(effects
				(font
					(size 1.27 1.27)
				)
			)
		)
		(property "Value" ""
			(at 0 0 180)
			(layer "F.Fab")
			(effects
				(font
					(size 1.27 1.27)
				)
			)
		)
		(duplicate_pad_numbers_are_jumpers no)
		(fp_line
			(start 0.7874 0.4064)
			(end -0.7874 0.4064)
			(stroke
				(width 0.1524)
				(type default)
			)
			(layer "F.SilkS")
		)
		(fp_line
			(start 0.7874 -0.4064)
			(end 0.7874 0.4064)
			(stroke
				(width 0.1524)
				(type default)
			)
			(layer "F.SilkS")
		)
		(fp_line
			(start -0.7874 0.4064)
			(end -0.7874 -0.4064)
			(stroke
				(width 0.1524)
				(type default)
			)
			(layer "F.SilkS")
		)
		(fp_line
			(start -0.7874 -0.4064)
			(end 0.7874 -0.4064)
			(stroke
				(width 0.1524)
				(type default)
			)
			(layer "F.SilkS")
		)
		(fp_line
			(start 0.67945 0.3048)
			(end 0.120396 0.3048)
			(stroke
				(width 0.1)
				(type default)
			)
			(layer "F.Fab")
		)
		(fp_line
			(start 0.67945 -0.3048)
			(end 0.67945 0.3048)
			(stroke
				(width 0.1)
				(type default)
			)
			(layer "F.Fab")
		)
		(fp_line
			(start 0.12065 -0.2794)
			(end 0.12065 -0.3048)
			(stroke
				(width 0.1)
				(type default)
			)
			(layer "F.Fab")
		)
		(fp_line
			(start 0.12065 -0.3048)
			(end 0.67945 -0.3048)
			(stroke
				(width 0.1)
				(type default)
			)
			(layer "F.Fab")
		)
		(fp_line
			(start 0.120396 0.3048)
			(end 0.120396 0.2794)
			(stroke
				(width 0.1)
				(type default)
			)
			(layer "F.Fab")
		)
		(fp_line
			(start 0.120396 0.2794)
			(end -0.12065 0.2794)
			(stroke
				(width 0.1)
				(type default)
			)
			(layer "F.Fab")
		)
		(fp_line
			(start -0.12065 0.3048)
			(end -0.67945 0.3048)
			(stroke
				(width 0.1)
				(type default)
			)
			(layer "F.Fab")
		)
		(fp_line
			(start -0.12065 0.2794)
			(end -0.12065 0.3048)
			(stroke
				(width 0.1)
				(type default)
			)
			(layer "F.Fab")
		)
		(fp_line
			(start -0.12065 -0.2794)
			(end 0.12065 -0.2794)
			(stroke
				(width 0.1)
				(type default)
			)
			(layer "F.Fab")
		)
		(fp_line
			(start -0.12065 -0.305054)
			(end -0.12065 -0.2794)
			(stroke
				(width 0.1)
				(type default)
			)
			(layer "F.Fab")
		)
		(fp_line
			(start -0.67945 0.3048)
			(end -0.67945 -0.305054)
			(stroke
				(width 0.1)
				(type default)
			)
			(layer "F.Fab")
		)
		(fp_line
			(start -0.67945 -0.305054)
			(end -0.12065 -0.305054)
			(stroke
				(width 0.1)
				(type default)
			)
			(layer "F.Fab")
		)
		(pad "1" smd circle
			(at -0.40005 0 180)
			(size 0 0)
			(layers "F.Cu" "F.Mask" "F.Paste")
			(net "P3V3_AUX")
		)
		(pad "2" smd circle
			(at 0.40005 0 180)
			(size 0 0)
			(layers "F.Cu" "F.Mask" "F.Paste")
			(net "IRQ_PVCCFA_CPU0_VRHOT_R_N")
		)
	)
	(footprint ""
		(layer "F.Cu")
		(at 464.01355 -45.669708)
		(property "Reference" "U82"
			(at -0.0127 1.719072 0)
			(unlocked yes)
			(layer "F.SilkS")
			(effects
				(font
					(size 0.7874 0.5842)
					(thickness 0.1524)
				)
				(justify left)
			)
		)
		(property "Value" ""
			(at 0 0 0)
			(layer "F.Fab")
			(effects
				(font
					(size 1.27 1.27)
				)
			)
		)
		(duplicate_pad_numbers_are_jumpers no)
		(fp_line
			(start -1.400048 1.100074)
			(end -1.400048 -1.100074)
			(stroke
				(width 0.1524)
				(type default)
			)
			(layer "F.SilkS")
		)
		(fp_line
			(start 1.400048 -1.100074)
			(end -1.400048 -1.100074)
			(stroke
				(width 0.1524)
				(type default)
			)
			(layer "F.SilkS")
		)
		(fp_line
			(start 1.400048 -1.100074)
			(end 1.400048 1.100074)
			(stroke
				(width 0.1524)
				(type default)
			)
			(layer "F.SilkS")
		)
		(fp_line
			(start 1.400048 1.100074)
			(end -1.400048 1.100074)
			(stroke
				(width 0.1524)
				(type default)
			)
			(layer "F.SilkS")
		)
		(fp_poly
			(pts
				(xy -2.606548 -0.141986) (xy -2.606548 -1.157986) (xy -1.590548 -0.649986)
			)
			(stroke
				(width 0)
				(type default)
			)
			(fill yes)
			(layer "F.SilkS")
		)
		(fp_line
			(start -0.674878 -1.100074)
			(end 0.674878 -1.100074)
			(stroke
				(width 0.1)
				(type default)
			)
			(layer "F.Fab")
		)
		(fp_line
			(start -0.674878 1.100074)
			(end -0.674878 -1.100074)
			(stroke
				(width 0.1)
				(type default)
			)
			(layer "F.Fab")
		)
		(fp_line
			(start 0.674878 -1.100074)
			(end 0.674878 1.100074)
			(stroke
				(width 0.1)
				(type default)
			)
			(layer "F.Fab")
		)
		(fp_line
			(start 0.674878 1.100074)
			(end -0.674878 1.100074)
			(stroke
				(width 0.1)
				(type default)
			)
			(layer "F.Fab")
		)
		(fp_poly
			(pts
				(xy -1.590548 -0.649986) (xy -2.606548 -1.157986) (xy -2.606548 -0.141986)
			)
			(stroke
				(width 0)
				(type default)
			)
			(fill yes)
			(layer "F.Fab")
		)
		(pad "1" smd rect
			(at -0.94996 -0.649986 270)
			(size 0.4318 0.6096)
			(layers "F.Cu" "F.Mask" "F.Paste")
			(net "PU_OCP_SFF_WAKE_OE")
		)
		(pad "2" smd rect
			(at -0.94996 0 270)
			(size 0.4318 0.6096)
			(layers "F.Cu" "F.Mask" "F.Paste")
			(net "IRQ_LVC3_OCP_SFF_WAKE_N")
		)
		(pad "3" smd rect
			(at -0.94996 0.649986 270)
			(size 0.4318 0.6096)
			(layers "F.Cu" "F.Mask" "F.Paste")
			(net "GND")
		)
		(pad "4" smd rect
			(at 0.94996 0.649986 270)
			(size 0.4318 0.6096)
			(layers "F.Cu" "F.Mask" "F.Paste")
			(net "OCP_SFF_WAKE_BUFF_N")
		)
		(pad "5" smd rect
			(at 0.94996 -0.649986 270)
			(size 0.4318 0.6096)
			(layers "F.Cu" "F.Mask" "F.Paste")
			(net "P3V3_AUX")
		)
	)
)
